#ISCELL
  logical_power design_note *
  *
#ISCELL
  mstr_misc dns *
  *
#ISCELL
  pure_quanta quanta_title_block_c *
  *
#ISCELL
  logical_power universal_power *
  page186_i10
#CELL
  pure_quanta q_res *
  page186_i11
#ISCELL
  standard offpage *
  page186_i14
#ISCELL
  logical_power universal_power *
  page186_i15
#CELL
  pure_quanta q_res *
  page186_i16
#ISCELL
  standard offpage *
  page186_i41
#ISCELL
  logical_power universal_power *
  page186_i44
#CELL
  pure_quanta q_res *
  page186_i45
#CELL
  pure_quanta q_res *
  page186_i46
#ISCELL
  logical_power universal_gnd *
  page186_i47
#ISCELL
  logical_power universal_power *
  page186_i58
#ISCELL
  standard offpage *
  page186_i59
#CELL
  pure_quanta q_res *
  page186_i60
#CELL
  pure_quanta q_res *
  page186_i61
#ISCELL
  logical_power universal_gnd *
  page186_i62
#ISCELL
  standard offpage *
  page186_i64
#ISCELL
  logical_power universal_power *
  page186_i65
#CELL
  pure_quanta q_res *
  page186_i68
#ISCELL
  standard offpage *
  page186_i72
#ISCELL
  logical_power universal_power *
  page186_i73
#ISCELL
  logical_power universal_gnd *
  page186_i74
#CELL
  pure_quanta q_res *
  page186_i76
#CELL
  pure_quanta q_res *
  page186_i77
#CELL
  pure_quanta q_res *
  page186_i78
#ISCELL
  standard offpage *
  page186_i79
#ISCELL
  standard offpage *
  page186_i8
#ISCELL
  logical_power universal_power *
  page186_i80
#CELL
  pure_quanta q_res *
  page186_i81
#ISCELL
  logical_power universal_gnd *
  page186_i82
#ISCELL
  standard offpage *
  page186_i84
#ISCELL
  logical_power universal_power *
  page186_i85
#ISCELL
  logical_power universal_gnd *
  page186_i87
#CELL
  pure_quanta q_res *
  page186_i88
#CELL
  pure_quanta q_res *
  page186_i89
#CELL
  pure_quanta q_res *
  page186_i90
#ISCELL
  logical_power universal_gnd *
  page186_i91
#CELL
  pure_quanta q_res *
  page186_i92
#ISCELL
  logical_power universal_gnd *
  page186_i93
